(kicad_pcb
	(version 20260206)
	(generator "pcbnew")
	(generator_version "10.0")
	(general
		(thickness 1.6)
		(legacy_teardrops no)
	)
	(paper "A4")
	(title_block
		(title "03242023_DA0F0TMBIJ0_F0T_Motherboard_J_brd_V01_OCP.brd")
		(comment 1 "Grand Teton / footprints 484-490 of 6105")
	)
	(layers
		(0 "F.Cu" signal "TOP")
		(4 "In1.Cu" signal "GND")
		(6 "In2.Cu" signal "IN1")
		(8 "In3.Cu" signal "GND1")
		(10 "In4.Cu" signal "IN2")
		(12 "In5.Cu" signal "GND2")
		(14 "In6.Cu" signal "IN3")
		(16 "In7.Cu" signal "GND3")
		(18 "In8.Cu" signal "VCC")
		(20 "In9.Cu" signal "VCC1")
		(22 "In10.Cu" signal "GND4")
		(24 "In11.Cu" signal "IN4")
		(26 "In12.Cu" signal "GND5")
		(28 "In13.Cu" signal "IN5")
		(30 "In14.Cu" signal "GND6")
		(32 "In15.Cu" signal "IN6")
		(34 "In16.Cu" signal "GND7")
		(2 "B.Cu" signal "BOTTOM")
		(9 "F.Adhes" user "F.Adhesive")
		(11 "B.Adhes" user "B.Adhesive")
		(13 "F.Paste" user "Package Geometry/Pastemask Top")
		(15 "B.Paste" user "Package Geometry/Pastemask Bottom")
		(5 "F.SilkS" user "Ref Des/Silkscreen Top")
		(7 "B.SilkS" user "Ref Des/Silkscreen Bottom")
		(1 "F.Mask" user "Board Geometry/Soldermask Top")
		(3 "B.Mask" user "Board Geometry/Soldermask Bottom")
		(17 "Dwgs.User" user "User.Drawings")
		(19 "Cmts.User" user "User.Comments")
		(21 "Eco1.User" user "User.Eco1")
		(23 "Eco2.User" user "User.Eco2")
		(25 "Edge.Cuts" user "Board Geometry/Outline")
		(27 "Margin" user)
		(31 "F.CrtYd" user "Package Geometry/Place Bound Top")
		(29 "B.CrtYd" user "Package Geometry/Place Bound Bottom")
		(35 "F.Fab" user "Ref Des/Assembly Top")
		(33 "B.Fab" user "Ref Des/Assembly Bottom")
	)
	(footprint ""
		(layer "F.Cu")
		(at 87.545926 -342.270334)
		(property "Reference" "PR291"
			(at 0 0 0)
			(layer "F.SilkS")
			(hide yes)
			(effects
				(font
					(size 1.27 1.27)
				)
			)
		)
		(property "Value" ""
			(at 0 0 0)
			(layer "F.Fab")
			(effects
				(font
					(size 1.27 1.27)
				)
			)
		)
		(duplicate_pad_numbers_are_jumpers no)
		(fp_line
			(start -0.7874 -0.4064)
			(end 0.7874 -0.4064)
			(stroke
				(width 0.1524)
				(type default)
			)
			(layer "F.SilkS")
		)
		(fp_line
			(start -0.7874 0.4064)
			(end -0.7874 -0.4064)
			(stroke
				(width 0.1524)
				(type default)
			)
			(layer "F.SilkS")
		)
		(fp_line
			(start 0.7874 -0.4064)
			(end 0.7874 0.4064)
			(stroke
				(width 0.1524)
				(type default)
			)
			(layer "F.SilkS")
		)
		(fp_line
			(start 0.7874 0.4064)
			(end -0.7874 0.4064)
			(stroke
				(width 0.1524)
				(type default)
			)
			(layer "F.SilkS")
		)
		(fp_line
			(start -0.67945 -0.305054)
			(end -0.12065 -0.305054)
			(stroke
				(width 0.1)
				(type default)
			)
			(layer "F.Fab")
		)
		(fp_line
			(start -0.67945 0.3048)
			(end -0.67945 -0.305054)
			(stroke
				(width 0.1)
				(type default)
			)
			(layer "F.Fab")
		)
		(fp_line
			(start -0.12065 -0.305054)
			(end -0.12065 -0.2794)
			(stroke
				(width 0.1)
				(type default)
			)
			(layer "F.Fab")
		)
		(fp_line
			(start -0.12065 -0.2794)
			(end 0.12065 -0.2794)
			(stroke
				(width 0.1)
				(type default)
			)
			(layer "F.Fab")
		)
		(fp_line
			(start -0.12065 0.2794)
			(end -0.12065 0.3048)
			(stroke
				(width 0.1)
				(type default)
			)
			(layer "F.Fab")
		)
		(fp_line
			(start -0.12065 0.3048)
			(end -0.67945 0.3048)
			(stroke
				(width 0.1)
				(type default)
			)
			(layer "F.Fab")
		)
		(fp_line
			(start 0.120396 0.2794)
			(end -0.12065 0.2794)
			(stroke
				(width 0.1)
				(type default)
			)
			(layer "F.Fab")
		)
		(fp_line
			(start 0.120396 0.3048)
			(end 0.120396 0.2794)
			(stroke
				(width 0.1)
				(type default)
			)
			(layer "F.Fab")
		)
		(fp_line
			(start 0.12065 -0.3048)
			(end 0.67945 -0.3048)
			(stroke
				(width 0.1)
				(type default)
			)
			(layer "F.Fab")
		)
		(fp_line
			(start 0.12065 -0.2794)
			(end 0.12065 -0.3048)
			(stroke
				(width 0.1)
				(type default)
			)
			(layer "F.Fab")
		)
		(fp_line
			(start 0.67945 -0.3048)
			(end 0.67945 0.3048)
			(stroke
				(width 0.1)
				(type default)
			)
			(layer "F.Fab")
		)
		(fp_line
			(start 0.67945 0.3048)
			(end 0.120396 0.3048)
			(stroke
				(width 0.1)
				(type default)
			)
			(layer "F.Fab")
		)
		(pad "1" smd circle
			(at -0.40005 0)
			(size 0 0)
			(layers "F.Cu" "F.Mask" "F.Paste")
			(net "PVCCIN_CPU1_LSET6")
		)
		(pad "2" smd circle
			(at 0.40005 0)
			(size 0 0)
			(layers "F.Cu" "F.Mask" "F.Paste")
			(net "GND")
		)
	)
	(footprint ""
		(layer "F.Cu")
		(at 51.593496 -112.33277)
		(property "Reference" "R3726"
			(at 0 0 0)
			(layer "F.SilkS")
			(hide yes)
			(effects
				(font
					(size 1.27 1.27)
				)
			)
		)
		(property "Value" ""
			(at 0 0 0)
			(layer "F.Fab")
			(effects
				(font
					(size 1.27 1.27)
				)
			)
		)
		(duplicate_pad_numbers_are_jumpers no)
		(fp_line
			(start -0.7874 -0.4064)
			(end 0.7874 -0.4064)
			(stroke
				(width 0.1524)
				(type default)
			)
			(layer "F.SilkS")
		)
		(fp_line
			(start -0.7874 0.4064)
			(end -0.7874 -0.4064)
			(stroke
				(width 0.1524)
				(type default)
			)
			(layer "F.SilkS")
		)
		(fp_line
			(start 0.7874 -0.4064)
			(end 0.7874 0.4064)
			(stroke
				(width 0.1524)
				(type default)
			)
			(layer "F.SilkS")
		)
		(fp_line
			(start 0.7874 0.4064)
			(end -0.7874 0.4064)
			(stroke
				(width 0.1524)
				(type default)
			)
			(layer "F.SilkS")
		)
		(fp_line
			(start -0.67945 -0.305054)
			(end -0.12065 -0.305054)
			(stroke
				(width 0.1)
				(type default)
			)
			(layer "F.Fab")
		)
		(fp_line
			(start -0.67945 0.3048)
			(end -0.67945 -0.305054)
			(stroke
				(width 0.1)
				(type default)
			)
			(layer "F.Fab")
		)
		(fp_line
			(start -0.12065 -0.305054)
			(end -0.12065 -0.2794)
			(stroke
				(width 0.1)
				(type default)
			)
			(layer "F.Fab")
		)
		(fp_line
			(start -0.12065 -0.2794)
			(end 0.12065 -0.2794)
			(stroke
				(width 0.1)
				(type default)
			)
			(layer "F.Fab")
		)
		(fp_line
			(start -0.12065 0.2794)
			(end -0.12065 0.3048)
			(stroke
				(width 0.1)
				(type default)
			)
			(layer "F.Fab")
		)
		(fp_line
			(start -0.12065 0.3048)
			(end -0.67945 0.3048)
			(stroke
				(width 0.1)
				(type default)
			)
			(layer "F.Fab")
		)
		(fp_line
			(start 0.120396 0.2794)
			(end -0.12065 0.2794)
			(stroke
				(width 0.1)
				(type default)
			)
			(layer "F.Fab")
		)
		(fp_line
			(start 0.120396 0.3048)
			(end 0.120396 0.2794)
			(stroke
				(width 0.1)
				(type default)
			)
			(layer "F.Fab")
		)
		(fp_line
			(start 0.12065 -0.3048)
			(end 0.67945 -0.3048)
			(stroke
				(width 0.1)
				(type default)
			)
			(layer "F.Fab")
		)
		(fp_line
			(start 0.12065 -0.2794)
			(end 0.12065 -0.3048)
			(stroke
				(width 0.1)
				(type default)
			)
			(layer "F.Fab")
		)
		(fp_line
			(start 0.67945 -0.3048)
			(end 0.67945 0.3048)
			(stroke
				(width 0.1)
				(type default)
			)
			(layer "F.Fab")
		)
		(fp_line
			(start 0.67945 0.3048)
			(end 0.120396 0.3048)
			(stroke
				(width 0.1)
				(type default)
			)
			(layer "F.Fab")
		)
		(pad "1" smd circle
			(at -0.40005 0)
			(size 0 0)
			(layers "F.Cu" "F.Mask" "F.Paste")
			(net "P3V3_AUX")
		)
		(pad "2" smd circle
			(at 0.40005 0)
			(size 0 0)
			(layers "F.Cu" "F.Mask" "F.Paste")
			(net "SMB_LM75_0_3V3AUX_SDA")
		)
	)
	(footprint ""
		(layer "F.Cu")
		(at 315.110622 -52.288948 180)
		(property "Reference" "R1263"
			(at 0 0 180)
			(layer "F.SilkS")
			(hide yes)
			(effects
				(font
					(size 1.27 1.27)
				)
			)
		)
		(property "Value" ""
			(at 0 0 180)
			(layer "F.Fab")
			(effects
				(font
					(size 1.27 1.27)
				)
			)
		)
		(duplicate_pad_numbers_are_jumpers no)
		(fp_line
			(start 0.7874 0.4064)
			(end -0.7874 0.4064)
			(stroke
				(width 0.1524)
				(type default)
			)
			(layer "F.SilkS")
		)
		(fp_line
			(start 0.7874 -0.4064)
			(end 0.7874 0.4064)
			(stroke
				(width 0.1524)
				(type default)
			)
			(layer "F.SilkS")
		)
		(fp_line
			(start -0.7874 0.4064)
			(end -0.7874 -0.4064)
			(stroke
				(width 0.1524)
				(type default)
			)
			(layer "F.SilkS")
		)
		(fp_line
			(start -0.7874 -0.4064)
			(end 0.7874 -0.4064)
			(stroke
				(width 0.1524)
				(type default)
			)
			(layer "F.SilkS")
		)
		(fp_line
			(start 0.67945 0.3048)
			(end 0.120396 0.3048)
			(stroke
				(width 0.1)
				(type default)
			)
			(layer "F.Fab")
		)
		(fp_line
			(start 0.67945 -0.3048)
			(end 0.67945 0.3048)
			(stroke
				(width 0.1)
				(type default)
			)
			(layer "F.Fab")
		)
		(fp_line
			(start 0.12065 -0.2794)
			(end 0.12065 -0.3048)
			(stroke
				(width 0.1)
				(type default)
			)
			(layer "F.Fab")
		)
		(fp_line
			(start 0.12065 -0.3048)
			(end 0.67945 -0.3048)
			(stroke
				(width 0.1)
				(type default)
			)
			(layer "F.Fab")
		)
		(fp_line
			(start 0.120396 0.3048)
			(end 0.120396 0.2794)
			(stroke
				(width 0.1)
				(type default)
			)
			(layer "F.Fab")
		)
		(fp_line
			(start 0.120396 0.2794)
			(end -0.12065 0.2794)
			(stroke
				(width 0.1)
				(type default)
			)
			(layer "F.Fab")
		)
		(fp_line
			(start -0.12065 0.3048)
			(end -0.67945 0.3048)
			(stroke
				(width 0.1)
				(type default)
			)
			(layer "F.Fab")
		)
		(fp_line
			(start -0.12065 0.2794)
			(end -0.12065 0.3048)
			(stroke
				(width 0.1)
				(type default)
			)
			(layer "F.Fab")
		)
		(fp_line
			(start -0.12065 -0.2794)
			(end 0.12065 -0.2794)
			(stroke
				(width 0.1)
				(type default)
			)
			(layer "F.Fab")
		)
		(fp_line
			(start -0.12065 -0.305054)
			(end -0.12065 -0.2794)
			(stroke
				(width 0.1)
				(type default)
			)
			(layer "F.Fab")
		)
		(fp_line
			(start -0.67945 0.3048)
			(end -0.67945 -0.305054)
			(stroke
				(width 0.1)
				(type default)
			)
			(layer "F.Fab")
		)
		(fp_line
			(start -0.67945 -0.305054)
			(end -0.12065 -0.305054)
			(stroke
				(width 0.1)
				(type default)
			)
			(layer "F.Fab")
		)
		(pad "1" smd circle
			(at -0.40005 0 180)
			(size 0 0)
			(layers "F.Cu" "F.Mask" "F.Paste")
			(net "FM_PLT_BMC_THERMTRIP_R_N")
		)
		(pad "2" smd circle
			(at 0.40005 0 180)
			(size 0 0)
			(layers "F.Cu" "F.Mask" "F.Paste")
			(net "FM_PCH_BMC_THERMTRIP_N")
		)
	)
	(footprint ""
		(layer "F.Cu")
		(at 104.277922 -338.86013)
		(property "Reference" "PR325"
			(at 0 0 0)
			(layer "F.SilkS")
			(hide yes)
			(effects
				(font
					(size 1.27 1.27)
				)
			)
		)
		(property "Value" ""
			(at 0 0 0)
			(layer "F.Fab")
			(effects
				(font
					(size 1.27 1.27)
				)
			)
		)
		(duplicate_pad_numbers_are_jumpers no)
		(fp_line
			(start -0.7874 -0.4064)
			(end 0.7874 -0.4064)
			(stroke
				(width 0.1524)
				(type default)
			)
			(layer "F.SilkS")
		)
		(fp_line
			(start -0.7874 0.4064)
			(end -0.7874 -0.4064)
			(stroke
				(width 0.1524)
				(type default)
			)
			(layer "F.SilkS")
		)
		(fp_line
			(start 0.7874 -0.4064)
			(end 0.7874 0.4064)
			(stroke
				(width 0.1524)
				(type default)
			)
			(layer "F.SilkS")
		)
		(fp_line
			(start 0.7874 0.4064)
			(end -0.7874 0.4064)
			(stroke
				(width 0.1524)
				(type default)
			)
			(layer "F.SilkS")
		)
		(fp_line
			(start -0.67945 -0.305054)
			(end -0.12065 -0.305054)
			(stroke
				(width 0.1)
				(type default)
			)
			(layer "F.Fab")
		)
		(fp_line
			(start -0.67945 0.3048)
			(end -0.67945 -0.305054)
			(stroke
				(width 0.1)
				(type default)
			)
			(layer "F.Fab")
		)
		(fp_line
			(start -0.12065 -0.305054)
			(end -0.12065 -0.2794)
			(stroke
				(width 0.1)
				(type default)
			)
			(layer "F.Fab")
		)
		(fp_line
			(start -0.12065 -0.2794)
			(end 0.12065 -0.2794)
			(stroke
				(width 0.1)
				(type default)
			)
			(layer "F.Fab")
		)
		(fp_line
			(start -0.12065 0.2794)
			(end -0.12065 0.3048)
			(stroke
				(width 0.1)
				(type default)
			)
			(layer "F.Fab")
		)
		(fp_line
			(start -0.12065 0.3048)
			(end -0.67945 0.3048)
			(stroke
				(width 0.1)
				(type default)
			)
			(layer "F.Fab")
		)
		(fp_line
			(start 0.120396 0.2794)
			(end -0.12065 0.2794)
			(stroke
				(width 0.1)
				(type default)
			)
			(layer "F.Fab")
		)
		(fp_line
			(start 0.120396 0.3048)
			(end 0.120396 0.2794)
			(stroke
				(width 0.1)
				(type default)
			)
			(layer "F.Fab")
		)
		(fp_line
			(start 0.12065 -0.3048)
			(end 0.67945 -0.3048)
			(stroke
				(width 0.1)
				(type default)
			)
			(layer "F.Fab")
		)
		(fp_line
			(start 0.12065 -0.2794)
			(end 0.12065 -0.3048)
			(stroke
				(width 0.1)
				(type default)
			)
			(layer "F.Fab")
		)
		(fp_line
			(start 0.67945 -0.3048)
			(end 0.67945 0.3048)
			(stroke
				(width 0.1)
				(type default)
			)
			(layer "F.Fab")
		)
		(fp_line
			(start 0.67945 0.3048)
			(end 0.120396 0.3048)
			(stroke
				(width 0.1)
				(type default)
			)
			(layer "F.Fab")
		)
		(pad "1" smd circle
			(at -0.40005 0)
			(size 0 0)
			(layers "F.Cu" "F.Mask" "F.Paste")
			(net "PVCCIN_CPU1_LSET2")
		)
		(pad "2" smd circle
			(at 0.40005 0)
			(size 0 0)
			(layers "F.Cu" "F.Mask" "F.Paste")
			(net "GND")
		)
	)
	(footprint ""
		(layer "F.Cu")
		(at 31.29788 -433.923948)
		(property "Reference" "R3466"
			(at 0 0 0)
			(layer "F.SilkS")
			(hide yes)
			(effects
				(font
					(size 1.27 1.27)
				)
			)
		)
		(property "Value" ""
			(at 0 0 0)
			(layer "F.Fab")
			(effects
				(font
					(size 1.27 1.27)
				)
			)
		)
		(duplicate_pad_numbers_are_jumpers no)
		(fp_line
			(start -0.7874 -0.4064)
			(end 0.7874 -0.4064)
			(stroke
				(width 0.1524)
				(type default)
			)
			(layer "F.SilkS")
		)
		(fp_line
			(start -0.7874 0.4064)
			(end -0.7874 -0.4064)
			(stroke
				(width 0.1524)
				(type default)
			)
			(layer "F.SilkS")
		)
		(fp_line
			(start 0.7874 -0.4064)
			(end 0.7874 0.4064)
			(stroke
				(width 0.1524)
				(type default)
			)
			(layer "F.SilkS")
		)
		(fp_line
			(start 0.7874 0.4064)
			(end -0.7874 0.4064)
			(stroke
				(width 0.1524)
				(type default)
			)
			(layer "F.SilkS")
		)
		(fp_line
			(start -0.67945 -0.305054)
			(end -0.12065 -0.305054)
			(stroke
				(width 0.1)
				(type default)
			)
			(layer "F.Fab")
		)
		(fp_line
			(start -0.67945 0.3048)
			(end -0.67945 -0.305054)
			(stroke
				(width 0.1)
				(type default)
			)
			(layer "F.Fab")
		)
		(fp_line
			(start -0.12065 -0.305054)
			(end -0.12065 -0.2794)
			(stroke
				(width 0.1)
				(type default)
			)
			(layer "F.Fab")
		)
		(fp_line
			(start -0.12065 -0.2794)
			(end 0.12065 -0.2794)
			(stroke
				(width 0.1)
				(type default)
			)
			(layer "F.Fab")
		)
		(fp_line
			(start -0.12065 0.2794)
			(end -0.12065 0.3048)
			(stroke
				(width 0.1)
				(type default)
			)
			(layer "F.Fab")
		)
		(fp_line
			(start -0.12065 0.3048)
			(end -0.67945 0.3048)
			(stroke
				(width 0.1)
				(type default)
			)
			(layer "F.Fab")
		)
		(fp_line
			(start 0.120396 0.2794)
			(end -0.12065 0.2794)
			(stroke
				(width 0.1)
				(type default)
			)
			(layer "F.Fab")
		)
		(fp_line
			(start 0.120396 0.3048)
			(end 0.120396 0.2794)
			(stroke
				(width 0.1)
				(type default)
			)
			(layer "F.Fab")
		)
		(fp_line
			(start 0.12065 -0.3048)
			(end 0.67945 -0.3048)
			(stroke
				(width 0.1)
				(type default)
			)
			(layer "F.Fab")
		)
		(fp_line
			(start 0.12065 -0.2794)
			(end 0.12065 -0.3048)
			(stroke
				(width 0.1)
				(type default)
			)
			(layer "F.Fab")
		)
		(fp_line
			(start 0.67945 -0.3048)
			(end 0.67945 0.3048)
			(stroke
				(width 0.1)
				(type default)
			)
			(layer "F.Fab")
		)
		(fp_line
			(start 0.67945 0.3048)
			(end 0.120396 0.3048)
			(stroke
				(width 0.1)
				(type default)
			)
			(layer "F.Fab")
		)
		(pad "1" smd circle
			(at -0.40005 0)
			(size 0 0)
			(layers "F.Cu" "F.Mask" "F.Paste")
			(net "RST_PERST_2_SWB_BUF_R_N")
		)
		(pad "2" smd circle
			(at 0.40005 0)
			(size 0 0)
			(layers "F.Cu" "F.Mask" "F.Paste")
			(net "GND")
		)
	)
	(footprint ""
		(layer "F.Cu")
		(at 12.530582 -423.629836 -90)
		(property "Reference" "R2983"
			(at 0 0 270)
			(layer "F.SilkS")
			(hide yes)
			(effects
				(font
					(size 1.27 1.27)
				)
			)
		)
		(property "Value" ""
			(at 0 0 270)
			(layer "F.Fab")
			(effects
				(font
					(size 1.27 1.27)
				)
			)
		)
		(duplicate_pad_numbers_are_jumpers no)
		(fp_line
			(start -0.7874 0.4064)
			(end -0.7874 -0.4064)
			(stroke
				(width 0.1524)
				(type default)
			)
			(layer "F.SilkS")
		)
		(fp_line
			(start 0.7874 0.4064)
			(end -0.7874 0.4064)
			(stroke
				(width 0.1524)
				(type default)
			)
			(layer "F.SilkS")
		)
		(fp_line
			(start -0.7874 -0.4064)
			(end 0.7874 -0.4064)
			(stroke
				(width 0.1524)
				(type default)
			)
			(layer "F.SilkS")
		)
		(fp_line
			(start 0.7874 -0.4064)
			(end 0.7874 0.4064)
			(stroke
				(width 0.1524)
				(type default)
			)
			(layer "F.SilkS")
		)
		(fp_line
			(start -0.67945 0.3048)
			(end -0.67945 -0.305054)
			(stroke
				(width 0.1)
				(type default)
			)
			(layer "F.Fab")
		)
		(fp_line
			(start -0.12065 0.3048)
			(end -0.67945 0.3048)
			(stroke
				(width 0.1)
				(type default)
			)
			(layer "F.Fab")
		)
		(fp_line
			(start 0.120396 0.3048)
			(end 0.120396 0.2794)
			(stroke
				(width 0.1)
				(type default)
			)
			(layer "F.Fab")
		)
		(fp_line
			(start 0.67945 0.3048)
			(end 0.120396 0.3048)
			(stroke
				(width 0.1)
				(type default)
			)
			(layer "F.Fab")
		)
		(fp_line
			(start -0.12065 0.2794)
			(end -0.12065 0.3048)
			(stroke
				(width 0.1)
				(type default)
			)
			(layer "F.Fab")
		)
		(fp_line
			(start 0.120396 0.2794)
			(end -0.12065 0.2794)
			(stroke
				(width 0.1)
				(type default)
			)
			(layer "F.Fab")
		)
		(fp_line
			(start -0.12065 -0.2794)
			(end 0.12065 -0.2794)
			(stroke
				(width 0.1)
				(type default)
			)
			(layer "F.Fab")
		)
		(fp_line
			(start 0.12065 -0.2794)
			(end 0.12065 -0.3048)
			(stroke
				(width 0.1)
				(type default)
			)
			(layer "F.Fab")
		)
		(fp_line
			(start 0.12065 -0.3048)
			(end 0.67945 -0.3048)
			(stroke
				(width 0.1)
				(type default)
			)
			(layer "F.Fab")
		)
		(fp_line
			(start 0.67945 -0.3048)
			(end 0.67945 0.3048)
			(stroke
				(width 0.1)
				(type default)
			)
			(layer "F.Fab")
		)
		(fp_line
			(start -0.67945 -0.305054)
			(end -0.12065 -0.305054)
			(stroke
				(width 0.1)
				(type default)
			)
			(layer "F.Fab")
		)
		(fp_line
			(start -0.12065 -0.305054)
			(end -0.12065 -0.2794)
			(stroke
				(width 0.1)
				(type default)
			)
			(layer "F.Fab")
		)
		(pad "1" smd circle
			(at -0.40005 0 270)
			(size 0 0)
			(layers "F.Cu" "F.Mask" "F.Paste")
			(net "SMB_IOEXP_3V3AUX_SDA")
		)
		(pad "2" smd circle
			(at 0.40005 0 270)
			(size 0 0)
			(layers "F.Cu" "F.Mask" "F.Paste")
			(net "SMB_IOEXP_3V3AUX_SDA_R1")
		)
	)
	(footprint ""
		(layer "F.Cu")
		(at 100.50018 -435.600094)
		(property "Reference" "H92"
			(at -5.01396 -4.694428 0)
			(unlocked yes)
			(layer "F.SilkS")
			(effects
				(font
					(size 0.7874 0.5842)
					(thickness 0.1524)
				)
				(justify left)
			)
		)
		(property "Value" ""
			(at 0 0 0)
			(layer "F.Fab")
			(effects
				(font
					(size 1.27 1.27)
				)
			)
		)
		(duplicate_pad_numbers_are_jumpers no)
		(pad "1" thru_hole circle
			(at 0 0)
			(size 10.0076 10.0076)
			(drill 5.6134)
			(layers "*.Cu" "*.Mask")
			(remove_unused_layers no)
			(net "GND")
			(clearance -1.9431)
		)
	)
)
